FILE_TYPE = CONNECTIVITY;
{Allegro Design Entry HDL 17.2-2016 S081 (4005846) 1/11/2022}
"PAGE_NUMBER" = 86;
0"NC";
1"P12V_S3_AUX_CPU0_NVDIMM\g";
2"P3V3_AUX\g";
3"P12V_S3_AUX_CPU0_NVDIMM\g";
4"P3V3_AUX\g";
5"GND\g";
6"GND\g";
7"GND\g";
8"GND\g";
9"GND\g";
10"M_C_CPU0_SA_DQ<31:0>";
11"M_C_CPU0_SA_CB<7:0>";
12"M_C_CPU0_SB_CB<7:0>";
13"M_C_CPU0_SA_CA<6:0>";
14"M_C_CPU0_SB_CA<6:0>";
15"M_C_CPU0_SB_DQ<31:0>";
16"M_C_CPU0_SB_DQS_DP<9:0>";
17"M_C_CPU0_SA_DQS_DP<9:0>";
18"M_C_CPU0_SB_DQS_DN<9:0>";
19"M_C_CPU0_SA_DQS_DN<9:0>";
20"M_C_CPU0_CLK_DN<0>";
21"PD_CHC_CPU0_DIMM1_SAA";
22"I3C_SPD_DDRABCD_CPU0_LVC1_SDA";
23"M_C_CPU0_ALERT_N";
24"RST_M_CD_CPU0_FPGA_N";
25"I3C_SPD_DDRABCD_CPU0_LVC1_SCL_R5";
26"I3C_SPD_DDRABCD_CPU0_LVC1_SCL";
27"PWRGD_CHC_CPU0_DIMM1";
28"TP_CHC_CPU0_DIMM1_FRU_6";
29"M_C_CPU0_SB_DQ<21>";
30"M_C_CPU0_SA_DQS_DN<9>";
31"M_C_CPU0_SA_DQS_DN<8>";
32"M_C_CPU0_SA_DQS_DN<7>";
33"M_C_CPU0_SA_DQS_DN<6>";
34"M_C_CPU0_SA_DQS_DN<4>";
35"M_C_CPU0_SA_DQS_DN<5>";
36"M_C_CPU0_SA_DQS_DN<3>";
37"M_C_CPU0_SA_DQS_DN<2>";
38"M_C_CPU0_SA_DQS_DN<1>";
39"M_C_CPU0_SA_DQS_DN<0>";
40"M_C_CPU0_SB_DQS_DN<8>";
41"M_C_CPU0_SB_DQS_DN<9>";
42"M_C_CPU0_SB_DQS_DN<7>";
43"M_C_CPU0_SB_DQS_DN<6>";
44"M_C_CPU0_SB_DQS_DN<5>";
45"M_C_CPU0_SB_DQS_DN<4>";
46"M_C_CPU0_SB_DQS_DN<3>";
47"M_C_CPU0_SB_DQS_DN<2>";
48"M_C_CPU0_SB_DQS_DN<1>";
49"M_C_CPU0_SB_DQS_DN<0>";
50"M_C_CPU0_SA_DQS_DP<9>";
51"M_C_CPU0_SA_DQS_DP<8>";
52"M_C_CPU0_SA_DQS_DP<7>";
53"M_C_CPU0_SA_DQS_DP<6>";
54"M_C_CPU0_SA_DQS_DP<5>";
55"M_C_CPU0_SA_DQS_DP<4>";
56"M_C_CPU0_SA_DQS_DP<3>";
57"M_C_CPU0_SA_DQS_DP<2>";
58"M_C_CPU0_SA_DQS_DP<1>";
59"M_C_CPU0_SA_DQS_DP<0>";
60"M_C_CPU0_SB_DQS_DP<9>";
61"M_C_CPU0_SB_DQS_DP<8>";
62"M_C_CPU0_SB_DQS_DP<7>";
63"M_C_CPU0_SB_DQS_DP<6>";
64"M_C_CPU0_SB_DQS_DP<5>";
65"M_C_CPU0_SB_DQS_DP<4>";
66"M_C_CPU0_SB_DQS_DP<3>";
67"M_C_CPU0_SB_DQS_DP<2>";
68"M_C_CPU0_SB_DQS_DP<1>";
69"M_C_CPU0_SB_DQS_DP<0>";
70"M_C_CPU0_SA_DQ<18>";
71"M_C_CPU0_SA_DQ<13>";
72"M_C_CPU0_SB_CS_N<0>";
73"M_C_CPU0_SB_CB<6>";
74"M_C_CPU0_SA_DQ<19>";
75"M_C_CPU0_SB_CS_N<1>";
76"M_C_CPU0_SB_CA<1>";
77"M_C_CPU0_SB_CA<0>";
78"M_C_CPU0_SA_DQ<9>";
79"M_C_CPU0_SB_DQ<31>";
80"M_C_CPU0_SB_DQ<29>";
81"M_C_CPU0_SB_DQ<2>";
82"M_C_CPU0_SB_DQ<7>";
83"M_C_CPU0_SB_DQ<8>";
84"M_C_CPU0_SB_DQ<9>";
85"M_C_CPU0_SB_DQ<10>";
86"TP_CHC_CPU0_DIMM1_FRU_0";
87"TP_CHC_CPU0_DIMM1_FRU_1";
88"TP_CHC_CPU0_DIMM1_FRU_2";
89"TP_CHC_CPU0_DIMM1_FRU_3";
90"TP_CHC_CPU0_DIMM1_FRU_4";
91"TP_CHC_CPU0_DIMM1_FRU_5";
92"M_C_CPU0_SB_PAR";
93"M_C_CPU0_SA_PAR";
94"M_C_CPU0_SB_RSP<0>";
95"M_C_CPU0_SA_RSP<0>";
96"M_C_CPU0_SB_DQ<0>";
97"M_C_CPU0_SB_DQ<1>";
98"M_C_CPU0_SB_DQ<3>";
99"M_C_CPU0_SB_DQ<4>";
100"M_C_CPU0_SB_DQ<5>";
101"M_C_CPU0_SB_DQ<6>";
102"M_C_CPU0_SB_DQ<11>";
103"M_C_CPU0_SB_DQ<12>";
104"M_C_CPU0_SB_DQ<13>";
105"M_C_CPU0_SB_DQ<14>";
106"M_C_CPU0_SB_DQ<15>";
107"M_C_CPU0_SB_DQ<16>";
108"M_C_CPU0_SB_DQ<17>";
109"M_C_CPU0_SB_DQ<18>";
110"M_C_CPU0_SB_DQ<19>";
111"M_C_CPU0_SB_DQ<20>";
112"M_C_CPU0_SB_DQ<22>";
113"M_C_CPU0_SB_DQ<23>";
114"M_C_CPU0_SB_DQ<24>";
115"M_C_CPU0_SB_DQ<25>";
116"M_C_CPU0_SB_DQ<26>";
117"M_C_CPU0_SB_DQ<27>";
118"M_C_CPU0_SB_DQ<28>";
119"M_C_CPU0_SB_DQ<30>";
120"M_C_CPU0_SA_DQ<0>";
121"M_C_CPU0_SA_DQ<1>";
122"M_C_CPU0_SA_DQ<2>";
123"M_C_CPU0_SA_DQ<3>";
124"M_C_CPU0_SA_DQ<4>";
125"M_C_CPU0_SA_DQ<5>";
126"M_C_CPU0_SA_DQ<6>";
127"M_C_CPU0_SA_DQ<7>";
128"M_C_CPU0_SA_DQ<8>";
129"M_C_CPU0_SA_DQ<10>";
130"M_C_CPU0_SA_DQ<11>";
131"M_C_CPU0_SA_DQ<12>";
132"M_C_CPU0_SA_DQ<14>";
133"M_C_CPU0_SA_DQ<15>";
134"M_C_CPU0_SA_DQ<16>";
135"M_C_CPU0_SA_DQ<17>";
136"M_C_CPU0_SA_DQ<20>";
137"M_C_CPU0_SA_DQ<21>";
138"M_C_CPU0_SA_DQ<22>";
139"M_C_CPU0_SA_DQ<23>";
140"M_C_CPU0_SA_DQ<24>";
141"M_C_CPU0_SA_DQ<25>";
142"M_C_CPU0_SA_DQ<26>";
143"M_C_CPU0_SA_DQ<27>";
144"M_C_CPU0_SA_DQ<28>";
145"M_C_CPU0_SA_DQ<29>";
146"M_C_CPU0_SA_DQ<30>";
147"M_C_CPU0_SA_CS_N<1>";
148"M_C_CPU0_SA_CS_N<0>";
149"M_C_CPU0_CLK_DP<0>";
150"M_C_CPU0_SB_CB<0>";
151"M_C_CPU0_SB_CB<1>";
152"M_C_CPU0_SB_CB<2>";
153"M_C_CPU0_SB_CB<3>";
154"M_C_CPU0_SB_CB<4>";
155"M_C_CPU0_SB_CB<5>";
156"M_C_CPU0_SA_CB<0>";
157"M_C_CPU0_SA_CB<2>";
158"M_C_CPU0_SA_CB<3>";
159"M_C_CPU0_SA_CB<5>";
160"M_C_CPU0_SA_CB<6>";
161"M_C_CPU0_SB_CA<6>";
162"M_C_CPU0_SA_CA<6>";
163"M_C_CPU0_SB_CA<5>";
164"M_C_CPU0_SA_CA<5>";
165"M_C_CPU0_SB_CA<4>";
166"M_C_CPU0_SA_CA<4>";
167"M_C_CPU0_SB_CA<3>";
168"M_C_CPU0_SA_CA<3>";
169"M_C_CPU0_SB_CA<2>";
170"M_C_CPU0_SA_CA<2>";
171"M_C_CPU0_SA_CA<1>";
172"M_C_CPU0_SA_CA<0>";
173"M_C_CPU0_SB_CB<7>";
174"M_C_CPU0_SA_CB<1>";
175"M_C_CPU0_SA_CB<4>";
176"M_C_CPU0_SA_CB<7>";
177"M_C_CPU0_SA_DQ<31>";
178"PD_CHC_CPU0_DIMM1_SAA";
%"TAP"
"1","(-1225,3300)","0","standard","I100";
;
CDS_LIB"standard"
BODY_TYPE"PLUMBING"
HDL_TAP"TRUE";
"B \NAC \NWC"10;
"S \NAC"
BN"14"132;
%"TAP"
"1","(-1225,3200)","0","standard","I101";
;
CDS_LIB"standard"
BODY_TYPE"PLUMBING"
HDL_TAP"TRUE";
"B \NAC \NWC"10;
"S \NAC"
BN"12"131;
%"TAP"
"1","(-1225,3350)","0","standard","I102";
;
CDS_LIB"standard"
BODY_TYPE"PLUMBING"
HDL_TAP"TRUE";
"B \NAC \NWC"10;
"S \NAC"
BN"15"133;
%"TAP"
"1","(-1225,3400)","0","standard","I103";
;
CDS_LIB"standard"
BODY_TYPE"PLUMBING"
HDL_TAP"TRUE";
"B \NAC \NWC"10;
"S \NAC"
BN"16"134;
%"TAP"
"1","(-1225,3550)","0","standard","I104";
;
CDS_LIB"standard"
BODY_TYPE"PLUMBING"
HDL_TAP"TRUE";
"B \NAC \NWC"10;
"S \NAC"
BN"19"74;
%"TAP"
"1","(-1225,3500)","0","standard","I105";
;
CDS_LIB"standard"
BODY_TYPE"PLUMBING"
HDL_TAP"TRUE";
"B \NAC \NWC"10;
"S \NAC"
BN"18"70;
%"TAP"
"1","(-1225,3450)","0","standard","I106";
;
CDS_LIB"standard"
BODY_TYPE"PLUMBING"
HDL_TAP"TRUE";
"B \NAC \NWC"10;
"S \NAC"
BN"17"135;
%"TAP"
"1","(-1225,3650)","0","standard","I107";
;
CDS_LIB"standard"
BODY_TYPE"PLUMBING"
HDL_TAP"TRUE";
"B \NAC \NWC"10;
"S \NAC"
BN"21"137;
%"TAP"
"1","(-1225,3600)","0","standard","I108";
;
CDS_LIB"standard"
BODY_TYPE"PLUMBING"
HDL_TAP"TRUE";
"B \NAC \NWC"10;
"S \NAC"
BN"20"136;
%"TAP"
"1","(-1225,3700)","0","standard","I109";
;
CDS_LIB"standard"
BODY_TYPE"PLUMBING"
HDL_TAP"TRUE";
"B \NAC \NWC"10;
"S \NAC"
BN"22"138;
%"TAP"
"1","(-1225,3750)","0","standard","I110";
;
CDS_LIB"standard"
BODY_TYPE"PLUMBING"
HDL_TAP"TRUE";
"B \NAC \NWC"10;
"S \NAC"
BN"23"139;
%"TAP"
"1","(-1225,3800)","0","standard","I111";
;
CDS_LIB"standard"
BODY_TYPE"PLUMBING"
HDL_TAP"TRUE";
"B \NAC \NWC"10;
"S \NAC"
BN"24"140;
%"TAP"
"1","(-1225,3850)","0","standard","I112";
;
CDS_LIB"standard"
BODY_TYPE"PLUMBING"
HDL_TAP"TRUE";
"B \NAC \NWC"10;
"S \NAC"
BN"25"141;
%"TAP"
"1","(-1225,3900)","0","standard","I113";
;
CDS_LIB"standard"
BODY_TYPE"PLUMBING"
HDL_TAP"TRUE";
"B \NAC \NWC"10;
"S \NAC"
BN"26"142;
%"TAP"
"1","(-1225,4050)","0","standard","I114";
;
CDS_LIB"standard"
BODY_TYPE"PLUMBING"
HDL_TAP"TRUE";
"B \NAC \NWC"10;
"S \NAC"
BN"29"145;
%"TAP"
"1","(-1225,3950)","0","standard","I115";
;
CDS_LIB"standard"
BODY_TYPE"PLUMBING"
HDL_TAP"TRUE";
"B \NAC \NWC"10;
"S \NAC"
BN"27"143;
%"TAP"
"1","(-1225,4000)","0","standard","I116";
;
CDS_LIB"standard"
BODY_TYPE"PLUMBING"
HDL_TAP"TRUE";
"B \NAC \NWC"10;
"S \NAC"
BN"28"144;
%"TAP"
"1","(-1225,4150)","0","standard","I117";
;
CDS_LIB"standard"
BODY_TYPE"PLUMBING"
HDL_TAP"TRUE";
"B \NAC \NWC"10;
"S \NAC"
BN"31"177;
%"TAP"
"1","(-1225,4100)","0","standard","I118";
;
CDS_LIB"standard"
BODY_TYPE"PLUMBING"
HDL_TAP"TRUE";
"B \NAC \NWC"10;
"S \NAC"
BN"30"146;
%"UNIVERSAL_GND"
"1","(500,-100)","0","logical_power","I119";
;
CDS_LIB"logical_power"
HDL_POWER"GND";
"A"9;
%"VCC_CORE"
"1","(-3700,2025)","0","logical_power","I12";
;
HDL_POWER"P3V3_AUX"
CDS_LIB"logical_power";
"A"2;
%"Q_CAP"
"1","(500,275)","0","pure_quanta","I120";
;
PART_NUMBER"CH5221MEB00"
PACK_TYPE"C0402"
TOLERANCE"20%"
VALUE"2.2UF"
MATERIAL"X6S"
VOLTAGE"6.3V"
$LOCATION"C14"
CDS_LIB"pure_quanta"
CDS_LOCATION"C14"
$SEC"1"
CDS_SEC"1";
"B"
$PN"2"9;
"A"
$PN"1"4;
%"Q_CAP"
"1","(1500,275)","0","pure_quanta","I121";
;
PART_NUMBER"CH6103KEA00"
VOLTAGE"16V"
VALUE"10UF"
TOLERANCE"10%"
MATERIAL"X6S"
PACK_TYPE"C0805"
$LOCATION"C15"
CDS_LIB"pure_quanta"
CDS_LOCATION"C15"
$SEC"1"
CDS_SEC"1";
"B"
$PN"2"8;
"A"
$PN"1"1;
%"UNIVERSAL_GND"
"1","(2125,-100)","0","logical_power","I122";
;
CDS_LIB"logical_power"
HDL_POWER"GND";
"A"8;
%"Q_CAP"
"1","(2125,275)","0","pure_quanta","I123";
;
PART_NUMBER"CH6103KEA00"
TOLERANCE"10%"
VALUE"10UF"
VOLTAGE"16V"
MATERIAL"X6S"
PACK_TYPE"C0805"
$LOCATION"C16"
CDS_LIB"pure_quanta"
CDS_LOCATION"C16"
$SEC"1"
CDS_SEC"1";
"B"
$PN"2"8;
"A"
$PN"1"1;
%"VCC_CORE"
"1","(500,600)","0","logical_power","I124";
;
HDL_POWER"P3V3_AUX"
CDS_LIB"logical_power";
"A"4;
%"VCC_CORE"
"1","(1500,600)","0","logical_power","I128";
;
HDL_POWER"P12V_S3_AUX_CPU0_NVDIMM"
CDS_LIB"logical_power";
"A"1;
%"TAP"
"1","(1525,2200)","0","standard","I129";
;
CDS_LIB"standard"
BODY_TYPE"PLUMBING"
HDL_TAP"TRUE";
"B \NAC \NWC"16;
"S \NAC"
BN"0"69;
%"TAP"
"1","(1700,2150)","0","standard","I130";
;
CDS_LIB"standard"
BODY_TYPE"PLUMBING"
HDL_TAP"TRUE";
"B \NAC \NWC"18;
"S \NAC"
BN"0"49;
%"TAP"
"1","(1700,2250)","0","standard","I131";
;
CDS_LIB"standard"
BODY_TYPE"PLUMBING"
HDL_TAP"TRUE";
"B \NAC \NWC"18;
"S \NAC"
BN"1"48;
%"TAP"
"1","(1525,2500)","0","standard","I132";
;
CDS_LIB"standard"
BODY_TYPE"PLUMBING"
HDL_TAP"TRUE";
"B \NAC \NWC"16;
"S \NAC"
BN"3"66;
%"TAP"
"1","(1525,2300)","0","standard","I133";
;
CDS_LIB"standard"
BODY_TYPE"PLUMBING"
HDL_TAP"TRUE";
"B \NAC \NWC"16;
"S \NAC"
BN"1"68;
%"TAP"
"1","(1525,2400)","0","standard","I134";
;
CDS_LIB"standard"
BODY_TYPE"PLUMBING"
HDL_TAP"TRUE";
"B \NAC \NWC"16;
"S \NAC"
BN"2"67;
%"TAP"
"1","(1525,2800)","0","standard","I135";
;
CDS_LIB"standard"
BODY_TYPE"PLUMBING"
HDL_TAP"TRUE";
"B \NAC \NWC"16;
"S \NAC"
BN"6"63;
%"TAP"
"1","(1525,2700)","0","standard","I136";
;
CDS_LIB"standard"
BODY_TYPE"PLUMBING"
HDL_TAP"TRUE";
"B \NAC \NWC"16;
"S \NAC"
BN"5"64;
%"TAP"
"1","(1525,2600)","0","standard","I137";
;
CDS_LIB"standard"
BODY_TYPE"PLUMBING"
HDL_TAP"TRUE";
"B \NAC \NWC"16;
"S \NAC"
BN"4"65;
%"TAP"
"1","(1525,2900)","0","standard","I138";
;
CDS_LIB"standard"
BODY_TYPE"PLUMBING"
HDL_TAP"TRUE";
"B \NAC \NWC"16;
"S \NAC"
BN"7"62;
%"TAP"
"1","(1525,3000)","0","standard","I139";
;
CDS_LIB"standard"
BODY_TYPE"PLUMBING"
HDL_TAP"TRUE";
"B \NAC \NWC"16;
"S \NAC"
BN"8"61;
%"TAP"
"1","(1525,3250)","0","standard","I140";
;
CDS_LIB"standard"
BODY_TYPE"PLUMBING"
HDL_TAP"TRUE";
"B \NAC \NWC"17;
"S \NAC"
BN"0"59;
%"TAP"
"1","(1525,3100)","0","standard","I141";
;
CDS_LIB"standard"
BODY_TYPE"PLUMBING"
HDL_TAP"TRUE";
"B \NAC \NWC"16;
"S \NAC"
BN"9"60;
%"TAP"
"1","(1700,2350)","0","standard","I142";
;
CDS_LIB"standard"
BODY_TYPE"PLUMBING"
HDL_TAP"TRUE";
"B \NAC \NWC"18;
"S \NAC"
BN"2"47;
%"TAP"
"1","(1700,2550)","0","standard","I143";
;
CDS_LIB"standard"
BODY_TYPE"PLUMBING"
HDL_TAP"TRUE";
"B \NAC \NWC"18;
"S \NAC"
BN"4"45;
%"TAP"
"1","(1700,2450)","0","standard","I144";
;
CDS_LIB"standard"
BODY_TYPE"PLUMBING"
HDL_TAP"TRUE";
"B \NAC \NWC"18;
"S \NAC"
BN"3"46;
%"TAP"
"1","(1700,2650)","0","standard","I145";
;
CDS_LIB"standard"
BODY_TYPE"PLUMBING"
HDL_TAP"TRUE";
"B \NAC \NWC"18;
"S \NAC"
BN"5"44;
%"TAP"
"1","(1700,2750)","0","standard","I146";
;
CDS_LIB"standard"
BODY_TYPE"PLUMBING"
HDL_TAP"TRUE";
"B \NAC \NWC"18;
"S \NAC"
BN"6"43;
%"TAP"
"1","(1700,2850)","0","standard","I147";
;
CDS_LIB"standard"
BODY_TYPE"PLUMBING"
HDL_TAP"TRUE";
"B \NAC \NWC"18;
"S \NAC"
BN"7"42;
%"TAP"
"1","(1700,3050)","0","standard","I148";
;
CDS_LIB"standard"
BODY_TYPE"PLUMBING"
HDL_TAP"TRUE";
"B \NAC \NWC"18;
"S \NAC"
BN"9"41;
%"TAP"
"1","(1700,2950)","0","standard","I149";
;
CDS_LIB"standard"
BODY_TYPE"PLUMBING"
HDL_TAP"TRUE";
"B \NAC \NWC"18;
"S \NAC"
BN"8"40;
%"TAP"
"1","(1700,3200)","0","standard","I150";
;
CDS_LIB"standard"
BODY_TYPE"PLUMBING"
HDL_TAP"TRUE";
"B \NAC \NWC"19;
"S \NAC"
BN"0"39;
%"TAP"
"1","(1700,3300)","0","standard","I151";
;
CDS_LIB"standard"
BODY_TYPE"PLUMBING"
HDL_TAP"TRUE";
"B \NAC \NWC"19;
"S \NAC"
BN"1"38;
%"TAP"
"1","(1525,3550)","0","standard","I152";
;
CDS_LIB"standard"
BODY_TYPE"PLUMBING"
HDL_TAP"TRUE";
"B \NAC \NWC"17;
"S \NAC"
BN"3"56;
%"TAP"
"1","(1525,3350)","0","standard","I153";
;
CDS_LIB"standard"
BODY_TYPE"PLUMBING"
HDL_TAP"TRUE";
"B \NAC \NWC"17;
"S \NAC"
BN"1"58;
%"TAP"
"1","(1525,3450)","0","standard","I154";
;
CDS_LIB"standard"
BODY_TYPE"PLUMBING"
HDL_TAP"TRUE";
"B \NAC \NWC"17;
"S \NAC"
BN"2"57;
%"TAP"
"1","(1525,3750)","0","standard","I155";
;
CDS_LIB"standard"
BODY_TYPE"PLUMBING"
HDL_TAP"TRUE";
"B \NAC \NWC"17;
"S \NAC"
BN"5"54;
%"TAP"
"1","(1525,3650)","0","standard","I156";
;
CDS_LIB"standard"
BODY_TYPE"PLUMBING"
HDL_TAP"TRUE";
"B \NAC \NWC"17;
"S \NAC"
BN"4"55;
%"TAP"
"1","(1525,3850)","0","standard","I157";
;
CDS_LIB"standard"
BODY_TYPE"PLUMBING"
HDL_TAP"TRUE";
"B \NAC \NWC"17;
"S \NAC"
BN"6"53;
%"TAP"
"1","(1525,3950)","0","standard","I158";
;
CDS_LIB"standard"
BODY_TYPE"PLUMBING"
HDL_TAP"TRUE";
"B \NAC \NWC"17;
"S \NAC"
BN"7"52;
%"TAP"
"1","(1525,4050)","0","standard","I159";
;
CDS_LIB"standard"
BODY_TYPE"PLUMBING"
HDL_TAP"TRUE";
"B \NAC \NWC"17;
"S \NAC"
BN"8"51;
%"TAP"
"1","(1525,4150)","0","standard","I160";
;
CDS_LIB"standard"
BODY_TYPE"PLUMBING"
HDL_TAP"TRUE";
"B \NAC \NWC"17;
"S \NAC"
BN"9"50;
%"TAP"
"1","(1700,3500)","0","standard","I161";
;
CDS_LIB"standard"
BODY_TYPE"PLUMBING"
HDL_TAP"TRUE";
"B \NAC \NWC"19;
"S \NAC"
BN"3"36;
%"TAP"
"1","(1700,3400)","0","standard","I162";
;
CDS_LIB"standard"
BODY_TYPE"PLUMBING"
HDL_TAP"TRUE";
"B \NAC \NWC"19;
"S \NAC"
BN"2"37;
%"TAP"
"1","(1700,3600)","0","standard","I163";
;
CDS_LIB"standard"
BODY_TYPE"PLUMBING"
HDL_TAP"TRUE";
"B \NAC \NWC"19;
"S \NAC"
BN"4"34;
%"TAP"
"1","(1700,3700)","0","standard","I164";
;
CDS_LIB"standard"
BODY_TYPE"PLUMBING"
HDL_TAP"TRUE";
"B \NAC \NWC"19;
"S \NAC"
BN"5"35;
%"TAP"
"1","(1700,3800)","0","standard","I165";
;
CDS_LIB"standard"
BODY_TYPE"PLUMBING"
HDL_TAP"TRUE";
"B \NAC \NWC"19;
"S \NAC"
BN"6"33;
%"TAP"
"1","(1700,3900)","0","standard","I166";
;
CDS_LIB"standard"
BODY_TYPE"PLUMBING"
HDL_TAP"TRUE";
"B \NAC \NWC"19;
"S \NAC"
BN"7"32;
%"TAP"
"1","(1700,4000)","0","standard","I167";
;
CDS_LIB"standard"
BODY_TYPE"PLUMBING"
HDL_TAP"TRUE";
"B \NAC \NWC"19;
"S \NAC"
BN"8"31;
%"TAP"
"1","(1700,4100)","0","standard","I168";
;
CDS_LIB"standard"
BODY_TYPE"PLUMBING"
HDL_TAP"TRUE";
"B \NAC \NWC"19;
"S \NAC"
BN"9"30;
%"UNIVERSAL_GND"
"1","(3200,450)","0","logical_power","I173";
;
CDS_LIB"logical_power"
HDL_POWER"GND";
"A"7;
%"SCONN288_ADR50017P130CC"
"3","(4050,2525)","0","pure_quanta","I174";
;
PART_NUMBER"DFHST8FS461"
MATERIAL"IO"
VALUE"SCONN288_ADR50017-P130CC"
PART_TYPE"SMLF"
$LOCATION"J5"
NEEDS_NO_SIZE"TRUE"
CDS_LMAN_SYM_OUTLINE"-450,1775,450,-1775"
CDS_LIB"pure_quanta"
CDS_LOCATION"J5"
$SEC"3"
CDS_SEC"3";
"G3"
$PN"G3"6;
"G2"
$PN"G2"6;
"G1"
$PN"G1"6;
"VSS62"
$PN"141"6;
"VSS61"
$PN"139"6;
"VSS60"
$PN"136"6;
"VSS58"
$PN"132"6;
"VSS104"
$PN"240"7;
"VSS102"
$PN"235"7;
"VSS100"
$PN"230"7;
"VIN_BULK2"
$PN"146"3;
"VIN_BULK1"
$PN"145"3;
"VIN_BULK0"
$PN"1"3;
"VSS126"
$PN"288"7;
"VSS125"
$PN"286"7;
"VSS124"
$PN"284"7;
"VSS123"
$PN"281"7;
"VSS122"
$PN"279"7;
"VSS121"
$PN"277"7;
"VSS120"
$PN"275"7;
"VSS119"
$PN"273"7;
"VSS118"
$PN"270"7;
"VSS117"
$PN"268"7;
"VSS116"
$PN"266"7;
"VSS115"
$PN"264"7;
"VSS114"
$PN"262"7;
"VSS113"
$PN"259"7;
"VSS112"
$PN"257"7;
"VSS111"
$PN"255"7;
"VSS110"
$PN"253"7;
"VSS109"
$PN"251"7;
"VSS108"
$PN"248"7;
"VSS107"
$PN"246"7;
"VSS106"
$PN"244"7;
"VSS105"
$PN"242"7;
"VSS103"
$PN"237"7;
"VSS101"
$PN"233"7;
"VSS99"
$PN"228"7;
"VSS98"
$PN"226"7;
"VSS97"
$PN"224"7;
"VSS96"
$PN"222"7;
"VSS95"
$PN"219"7;
"VSS94"
$PN"216"7;
"VSS93"
$PN"214"7;
"VSS92"
$PN"212"7;
"VSS91"
$PN"210"7;
"VSS90"
$PN"208"7;
"VSS89"
$PN"206"7;
"VSS88"
$PN"204"7;
"VSS87"
$PN"202"7;
"VSS86"
$PN"199"7;
"VSS85"
$PN"197"7;
"VSS84"
$PN"195"7;
"VSS83"
$PN"193"7;
"VSS82"
$PN"191"7;
"VSS81"
$PN"188"7;
"VSS80"
$PN"186"7;
"VSS79"
$PN"184"7;
"VSS78"
$PN"182"7;
"VSS77"
$PN"180"7;
"VSS76"
$PN"177"7;
"VSS75"
$PN"175"7;
"VSS74"
$PN"173"7;
"VSS73"
$PN"171"7;
"VSS72"
$PN"169"7;
"VSS71"
$PN"166"7;
"VSS70"
$PN"164"7;
"VSS69"
$PN"162"7;
"VSS68"
$PN"160"7;
"VSS67"
$PN"158"7;
"VSS66"
$PN"155"7;
"VSS65"
$PN"153"7;
"VSS64"
$PN"151"7;
"VSS63"
$PN"143"6;
"VSS59"
$PN"134"6;
"VSS57"
$PN"130"6;
"VSS56"
$PN"128"6;
"VSS55"
$PN"125"6;
"VSS54"
$PN"123"6;
"VSS53"
$PN"121"6;
"VSS52"
$PN"119"6;
"VSS51"
$PN"117"6;
"VSS50"
$PN"114"6;
"VSS49"
$PN"112"6;
"VSS48"
$PN"110"6;
"VSS47"
$PN"108"6;
"VSS46"
$PN"106"6;
"VSS45"
$PN"103"6;
"VSS44"
$PN"101"6;
"VSS43"
$PN"99"6;
"VSS42"
$PN"97"6;
"VSS41"
$PN"95"6;
"VSS40"
$PN"92"6;
"VSS39"
$PN"90"6;
"VSS38"
$PN"88"6;
"VSS37"
$PN"85"6;
"VSS36"
$PN"83"6;
"VSS35"
$PN"81"6;
"VSS34"
$PN"79"6;
"VSS33"
$PN"77"6;
"VSS32"
$PN"75"6;
"VSS31"
$PN"73"6;
"VSS30"
$PN"71"6;
"VSS29"
$PN"69"6;
"VSS28"
$PN"67"6;
"VSS27"
$PN"65"6;
"VSS26"
$PN"63"6;
"VSS25"
$PN"61"6;
"VSS24"
$PN"59"6;
"VSS23"
$PN"57"6;
"VSS22"
$PN"54"6;
"VSS21"
$PN"52"6;
"VSS20"
$PN"50"6;
"VSS19"
$PN"48"6;
"VSS18"
$PN"46"6;
"VSS17"
$PN"43"6;
"VSS16"
$PN"41"6;
"VSS15"
$PN"39"6;
"VSS14"
$PN"37"6;
"VSS13"
$PN"35"6;
"VSS12"
$PN"32"6;
"VSS11"
$PN"30"6;
"VSS10"
$PN"28"6;
"VSS9"
$PN"26"6;
"VSS8"
$PN"24"6;
"VSS7"
$PN"21"6;
"VSS6"
$PN"19"6;
"VSS5"
$PN"17"6;
"VSS4"
$PN"15"6;
"VSS3"
$PN"13"6;
"VSS2"
$PN"10"6;
"VSS1"
$PN"8"6;
"VSS0"
$PN"6"6;
%"UNIVERSAL_GND"
"1","(4900,450)","0","logical_power","I175";
;
CDS_LIB"logical_power"
HDL_POWER"GND";
"A"6;
%"VCC_CORE"
"1","(3200,4700)","0","logical_power","I176";
;
HDL_POWER"P12V_S3_AUX_CPU0_NVDIMM"
CDS_LIB"logical_power";
"A"3;
%"SCONN288_ADR50017P130CC"
"2","(625,3150)","0","pure_quanta","I178";
;
PART_NUMBER"DFHST8FS461"
MATERIAL"IO"
PART_TYPE"SMLF"
VALUE"SCONN288_ADR50017-P130CC"
LOCATION"J5"
NEEDS_NO_SIZE"TRUE"
CDS_LMAN_SYM_OUTLINE"-600,1150,600,-1150"
CDS_LIB"pure_quanta"
$SEC"2"
CDS_SEC"2";
"DQS7_A_C||TDQS7_A_C \B"
$PN"178"32;
"DQS6_A_T||TDQS6_A_T"
$PN"168"53;
"DQS8_B_T||TDQS8_B_T"
$PN"283"61;
"DQS8_B_C||TDQS8_B_C \B"
$PN"282"40;
"DQS7_B_T||TDQS7_B_T"
$PN"272"62;
"DQS0_A_C \B"
$PN"12"39;
"DQS0_A_T"
$PN"11"59;
"DQS0_B_C \B"
$PN"105"49;
"DQS0_B_T"
$PN"104"69;
"DQS1_A_C \B"
$PN"23"38;
"DQS1_A_T"
$PN"22"58;
"DQS1_B_C \B"
$PN"116"48;
"DQS1_B_T"
$PN"115"68;
"DQS2_A_C \B"
$PN"34"37;
"DQS2_A_T"
$PN"33"57;
"DQS2_B_C \B"
$PN"127"47;
"DQS2_B_T"
$PN"126"67;
"DQS3_A_C \B"
$PN"45"36;
"DQS3_A_T"
$PN"44"56;
"DQS3_B_C \B"
$PN"138"46;
"DQS3_B_T"
$PN"137"66;
"DQS4_A_C \B"
$PN"56"34;
"DQS4_A_T"
$PN"55"55;
"DQS4_B_C \B"
$PN"238"45;
"DQS4_B_T"
$PN"239"65;
"DQS5_A_C||TDQS5_A_C||DQS5_A_T||TDQS5_A_T \B"
$PN"156"35;
"DQS5_A_T||TDQS5_A_T"
$PN"157"54;
"DQS5_B_C||TDQS5_B_C \B"
$PN"249"44;
"DQS5_B_T||TDQS5_B_T"
$PN"250"64;
"DQS6_A_C||TDQS6_A_C||DQS6_A_T||TDQS6_A_T \B"
$PN"167"33;
"DQS6_B_C||TDQS6_B_C \B"
$PN"260"43;
"DQS6_B_T||TDQS6_B_T"
$PN"261"63;
"DQS7_A_T||TDQS7_A_T"
$PN"179"52;
"DQS7_B_C||TDQS7_B_C \B"
$PN"271"42;
"DQS8_A_C||TDQS8_A_C \B"
$PN"189"31;
"DQS8_A_T||TDQS8_A_T"
$PN"190"51;
"DQS9_A_C||TDQS9_A_C \B"
$PN"200"30;
"DQS9_A_T||TDQS9_A_T"
$PN"201"50;
"DQS9_B_C||TDQS9_B_C \B"
$PN"94"41;
"DQS9_B_T||TDQS9_B_T||DBI4_B_N"
$PN"93"60;
%"Q_RES"
"1","(-3925,1450)","0","pure_quanta","I180";
;
PART_NUMBER"CS04992FB07"
VALUE"49.9"
MATERIAL"CHIP"
$LOCATION"R3879"
CDS_LIB"pure_quanta"
PACK_TYPE"0402LF"
TOLERANCE"1%"
WATTAGE"1/16W"
CDS_LOCATION"R3879"
$SEC"1"
CDS_SEC"1";
"B"
$PN"2"26;
"A"
$PN"1"25;
%"UNIVERSAL_GND"
"1","(-2650,-225)","0","logical_power","I2";
;
CDS_LIB"logical_power"
HDL_POWER"GND";
"A"5;
%"SCONN288_ADR50017P130CC"
"1","(-2050,2425)","0","pure_quanta","I24";
;
PART_NUMBER"DFHST8FS461"
MATERIAL"IO"
VALUE"SCONN288_ADR50017-P130CC"
PART_TYPE"SMLF"
$LOCATION"J5"
NEEDS_NO_SIZE"TRUE"
CDS_LMAN_SYM_OUTLINE"-450,1875,450,-1875"
CDS_LIB"pure_quanta"
CDS_LOCATION"J5"
$SEC"1"
CDS_SEC"1";
"DQ31_A"
$PN"194"177;
"CB7_A"
$PN"205"176;
"CB4_A"
$PN"58"175;
"CB1_A"
$PN"53"174;
"CB7_B"
$PN"236"173;
"ALERT_N \B"
$PN"62"23;
"CA0_A"
$PN"66"172;
"CA0_B"
$PN"76"77;
"CA1_A"
$PN"211"171;
"CA1_B"
$PN"221"76;
"CA2_A"
$PN"68"170;
"CA2_B"
$PN"78"169;
"CA3_A"
$PN"213"168;
"CA3_B"
$PN"223"167;
"CA4_A"
$PN"70"166;
"CA4_B"
$PN"80"165;
"CA5_A"
$PN"215"164;
"CA5_B"
$PN"225"163;
"CA6_A"
$PN"72"162;
"CA6_B"
$PN"82"161;
"CB6_A"
$PN"203"160;
"CB5_A"
$PN"60"159;
"CB3_A"
$PN"198"158;
"CB2_A"
$PN"196"157;
"CB0_A"
$PN"51"156;
"CB6_B"
$PN"234"73;
"CB5_B"
$PN"91"155;
"CB4_B"
$PN"89"154;
"CB3_B"
$PN"243"153;
"CB2_B"
$PN"241"152;
"CB1_B"
$PN"98"151;
"CB0_B"
$PN"96"150;
"CK_C \B"
$PN"218"20;
"CK_T"
$PN"217"149;
"CS0_A_N"
$PN"64"148;
"CS0_B_N"
$PN"84"72;
"CS1_A_N"
$PN"209"147;
"CS1_B_N"
$PN"229"75;
"DQ30_A"
$PN"192"146;
"DQ29_A"
$PN"49"145;
"DQ28_A"
$PN"47"144;
"DQ27_A"
$PN"187"143;
"DQ26_A"
$PN"185"142;
"DQ25_A"
$PN"42"141;
"DQ24_A"
$PN"40"140;
"DQ23_A"
$PN"183"139;
"DQ22_A"
$PN"181"138;
"DQ21_A"
$PN"38"137;
"DQ20_A"
$PN"36"136;
"DQ19_A"
$PN"176"74;
"DQ18_A"
$PN"174"70;
"DQ17_A"
$PN"31"135;
"DQ16_A"
$PN"29"134;
"DQ15_A"
$PN"172"133;
"DQ14_A"
$PN"170"132;
"DQ13_A"
$PN"27"71;
"DQ12_A"
$PN"25"131;
"DQ11_A"
$PN"165"130;
"DQ10_A"
$PN"163"129;
"DQ9_A"
$PN"20"78;
"DQ8_A"
$PN"18"128;
"DQ7_A"
$PN"161"127;
"DQ6_A"
$PN"159"126;
"DQ5_A"
$PN"16"125;
"DQ4_A"
$PN"14"124;
"DQ3_A"
$PN"154"123;
"DQ2_A"
$PN"152"122;
"DQ1_A"
$PN"9"121;
"DQ0_A"
$PN"7"120;
"DQ31_B"
$PN"287"79;
"DQ30_B"
$PN"285"119;
"DQ29_B"
$PN"142"80;
"DQ28_B"
$PN"140"118;
"DQ27_B"
$PN"280"117;
"DQ26_B"
$PN"278"116;
"DQ25_B"
$PN"135"115;
"DQ24_B"
$PN"133"114;
"DQ23_B"
$PN"276"113;
"DQ22_B"
$PN"274"112;
"DQ21_B"
$PN"131"29;
"DQ20_B"
$PN"129"111;
"DQ19_B"
$PN"269"110;
"DQ18_B"
$PN"267"109;
"DQ17_B"
$PN"124"108;
"DQ16_B"
$PN"122"107;
"DQ15_B"
$PN"265"106;
"DQ14_B"
$PN"263"105;
"DQ13_B"
$PN"120"104;
"DQ12_B"
$PN"118"103;
"DQ11_B"
$PN"258"102;
"DQ10_B"
$PN"256"85;
"DQ9_B"
$PN"113"84;
"DQ8_B"
$PN"111"83;
"DQ7_B"
$PN"254"82;
"DQ6_B"
$PN"252"101;
"DQ5_B"
$PN"109"100;
"DQ4_B"
$PN"107"99;
"DQ3_B"
$PN"247"98;
"DQ2_B"
$PN"245"81;
"DQ1_B"
$PN"102"97;
"DQ0_B"
$PN"100"96;
"HSA"
$PN"148"21;
"HSCL"
$PN"4"25;
"HSDA"
$PN"5"22;
"LBD||RSP_A_N"
$PN"86"95;
"LBS||RSP_B_N"
$PN"87"94;
"PAR_A"
$PN"74"93;
"PAR_B"
$PN"227"92;
"PWR_GOOD||FAIL_N"
$PN"147"27;
"RESET_N \B"
$PN"207"24;
"RFU6"
$PN"232"28;
"RFU5"
$PN"231"91;
"RFU4"
$PN"220"90;
"RFU3"
$PN"150"89;
"RFU2"
$PN"149"88;
"RFU1"
$PN"144"87;
"RFU0"
$PN"2"86;
"VIN_MGMT"
$PN"3"2;
%"TAP"
"1","(-2875,1950)","2","standard","I25";
;
CDS_LIB"standard"
BODY_TYPE"PLUMBING"
HDL_TAP"TRUE";
"B \NAC \NWC"12;
"S \NAC"
BN"0"150;
%"TAP"
"1","(-2875,2000)","2","standard","I26";
;
CDS_LIB"standard"
BODY_TYPE"PLUMBING"
HDL_TAP"TRUE";
"B \NAC \NWC"12;
"S \NAC"
BN"1"151;
%"TAP"
"1","(-2875,2100)","2","standard","I27";
;
CDS_LIB"standard"
BODY_TYPE"PLUMBING"
HDL_TAP"TRUE";
"B \NAC \NWC"12;
"S \NAC"
BN"3"153;
%"TAP"
"1","(-2875,2050)","2","standard","I28";
;
CDS_LIB"standard"
BODY_TYPE"PLUMBING"
HDL_TAP"TRUE";
"B \NAC \NWC"12;
"S \NAC"
BN"2"152;
%"TAP"
"1","(-2875,2200)","2","standard","I29";
;
CDS_LIB"standard"
BODY_TYPE"PLUMBING"
HDL_TAP"TRUE";
"B \NAC \NWC"12;
"S \NAC"
BN"5"155;
%"Q_RES"
"2","(-2650,0)","0","pure_quanta","I3";
;
PART_NUMBER"CS35492FB03"
WATTAGE"1/16W"
MATERIAL"CHIP"
PACK_TYPE"0402LF"
TOLERANCE"1%"
VALUE"54.9K"
$LOCATION"R30"
CDS_LIB"pure_quanta"
CDS_LOCATION"R30"
$SEC"1"
CDS_SEC"1";
"A"
$PN"1"178;
"B"
$PN"2"5;
%"TAP"
"1","(-2875,2250)","2","standard","I30";
;
CDS_LIB"standard"
BODY_TYPE"PLUMBING"
HDL_TAP"TRUE";
"B \NAC \NWC"12;
"S \NAC"
BN"6"73;
%"TAP"
"1","(-2875,2150)","2","standard","I31";
;
CDS_LIB"standard"
BODY_TYPE"PLUMBING"
HDL_TAP"TRUE";
"B \NAC \NWC"12;
"S \NAC"
BN"4"154;
%"TAP"
"1","(-1225,1000)","0","standard","I32";
;
CDS_LIB"standard"
BODY_TYPE"PLUMBING"
HDL_TAP"TRUE";
"B \NAC \NWC"15;
"S \NAC"
BN"1"97;
%"TAP"
"1","(-1225,950)","0","standard","I33";
;
CDS_LIB"standard"
BODY_TYPE"PLUMBING"
HDL_TAP"TRUE";
"B \NAC \NWC"15;
"S \NAC"
BN"0"96;
%"TAP"
"1","(-1225,1100)","0","standard","I34";
;
CDS_LIB"standard"
BODY_TYPE"PLUMBING"
HDL_TAP"TRUE";
"B \NAC \NWC"15;
"S \NAC"
BN"3"98;
%"TAP"
"1","(-1225,1050)","0","standard","I35";
;
CDS_LIB"standard"
BODY_TYPE"PLUMBING"
HDL_TAP"TRUE";
"B \NAC \NWC"15;
"S \NAC"
BN"2"81;
%"TAP"
"1","(-1225,1150)","0","standard","I36";
;
CDS_LIB"standard"
BODY_TYPE"PLUMBING"
HDL_TAP"TRUE";
"B \NAC \NWC"15;
"S \NAC"
BN"4"99;
%"TAP"
"1","(-1225,1200)","0","standard","I37";
;
CDS_LIB"standard"
BODY_TYPE"PLUMBING"
HDL_TAP"TRUE";
"B \NAC \NWC"15;
"S \NAC"
BN"5"100;
%"TAP"
"1","(-1225,1250)","0","standard","I38";
;
CDS_LIB"standard"
BODY_TYPE"PLUMBING"
HDL_TAP"TRUE";
"B \NAC \NWC"15;
"S \NAC"
BN"6"101;
%"TAP"
"1","(-1225,1400)","0","standard","I39";
;
CDS_LIB"standard"
BODY_TYPE"PLUMBING"
HDL_TAP"TRUE";
"B \NAC \NWC"15;
"S \NAC"
BN"9"84;
%"TAP"
"1","(-1225,1300)","0","standard","I40";
;
CDS_LIB"standard"
BODY_TYPE"PLUMBING"
HDL_TAP"TRUE";
"B \NAC \NWC"15;
"S \NAC"
BN"7"82;
%"TAP"
"1","(-1225,1350)","0","standard","I41";
;
CDS_LIB"standard"
BODY_TYPE"PLUMBING"
HDL_TAP"TRUE";
"B \NAC \NWC"15;
"S \NAC"
BN"8"83;
%"TAP"
"1","(-1225,1500)","0","standard","I42";
;
CDS_LIB"standard"
BODY_TYPE"PLUMBING"
HDL_TAP"TRUE";
"B \NAC \NWC"15;
"S \NAC"
BN"11"102;
%"TAP"
"1","(-1225,1450)","0","standard","I43";
;
CDS_LIB"standard"
BODY_TYPE"PLUMBING"
HDL_TAP"TRUE";
"B \NAC \NWC"15;
"S \NAC"
BN"10"85;
%"TAP"
"1","(-1225,1600)","0","standard","I44";
;
CDS_LIB"standard"
BODY_TYPE"PLUMBING"
HDL_TAP"TRUE";
"B \NAC \NWC"15;
"S \NAC"
BN"13"104;
%"TAP"
"1","(-1225,1550)","0","standard","I45";
;
CDS_LIB"standard"
BODY_TYPE"PLUMBING"
HDL_TAP"TRUE";
"B \NAC \NWC"15;
"S \NAC"
BN"12"103;
%"TAP"
"1","(-1225,1650)","0","standard","I46";
;
CDS_LIB"standard"
BODY_TYPE"PLUMBING"
HDL_TAP"TRUE";
"B \NAC \NWC"15;
"S \NAC"
BN"14"105;
%"TAP"
"1","(-1225,1700)","0","standard","I47";
;
CDS_LIB"standard"
BODY_TYPE"PLUMBING"
HDL_TAP"TRUE";
"B \NAC \NWC"15;
"S \NAC"
BN"15"106;
%"TAP"
"1","(-1225,1750)","0","standard","I48";
;
CDS_LIB"standard"
BODY_TYPE"PLUMBING"
HDL_TAP"TRUE";
"B \NAC \NWC"15;
"S \NAC"
BN"16"107;
%"TAP"
"1","(-1225,1850)","0","standard","I49";
;
CDS_LIB"standard"
BODY_TYPE"PLUMBING"
HDL_TAP"TRUE";
"B \NAC \NWC"15;
"S \NAC"
BN"18"109;
%"TAP"
"1","(-1225,1800)","0","standard","I50";
;
CDS_LIB"standard"
BODY_TYPE"PLUMBING"
HDL_TAP"TRUE";
"B \NAC \NWC"15;
"S \NAC"
BN"17"108;
%"TAP"
"1","(-1225,1900)","0","standard","I51";
;
CDS_LIB"standard"
BODY_TYPE"PLUMBING"
HDL_TAP"TRUE";
"B \NAC \NWC"15;
"S \NAC"
BN"19"110;
%"TAP"
"1","(-1225,2000)","0","standard","I52";
;
CDS_LIB"standard"
BODY_TYPE"PLUMBING"
HDL_TAP"TRUE";
"B \NAC \NWC"15;
"S \NAC"
BN"21"29;
%"TAP"
"1","(-1225,1950)","0","standard","I53";
;
CDS_LIB"standard"
BODY_TYPE"PLUMBING"
HDL_TAP"TRUE";
"B \NAC \NWC"15;
"S \NAC"
BN"20"111;
%"TAP"
"1","(-1225,2150)","0","standard","I54";
;
CDS_LIB"standard"
BODY_TYPE"PLUMBING"
HDL_TAP"TRUE";
"B \NAC \NWC"15;
"S \NAC"
BN"24"114;
%"TAP"
"1","(-1225,2100)","0","standard","I55";
;
CDS_LIB"standard"
BODY_TYPE"PLUMBING"
HDL_TAP"TRUE";
"B \NAC \NWC"15;
"S \NAC"
BN"23"113;
%"TAP"
"1","(-1225,2050)","0","standard","I56";
;
CDS_LIB"standard"
BODY_TYPE"PLUMBING"
HDL_TAP"TRUE";
"B \NAC \NWC"15;
"S \NAC"
BN"22"112;
%"TAP"
"1","(-1225,2200)","0","standard","I57";
;
CDS_LIB"standard"
BODY_TYPE"PLUMBING"
HDL_TAP"TRUE";
"B \NAC \NWC"15;
"S \NAC"
BN"25"115;
%"TAP"
"1","(-1225,2250)","0","standard","I58";
;
CDS_LIB"standard"
BODY_TYPE"PLUMBING"
HDL_TAP"TRUE";
"B \NAC \NWC"15;
"S \NAC"
BN"26"116;
%"TAP"
"1","(-2875,2500)","2","standard","I59";
;
CDS_LIB"standard"
BODY_TYPE"PLUMBING"
HDL_TAP"TRUE";
"B \NAC \NWC"11;
"S \NAC"
BN"2"157;
%"TAP"
"1","(-2875,2450)","2","standard","I60";
;
CDS_LIB"standard"
BODY_TYPE"PLUMBING"
HDL_TAP"TRUE";
"B \NAC \NWC"11;
"S \NAC"
BN"1"174;
%"TAP"
"1","(-2875,2400)","2","standard","I61";
;
CDS_LIB"standard"
BODY_TYPE"PLUMBING"
HDL_TAP"TRUE";
"B \NAC \NWC"11;
"S \NAC"
BN"0"156;
%"TAP"
"1","(-2875,2300)","2","standard","I62";
;
CDS_LIB"standard"
BODY_TYPE"PLUMBING"
HDL_TAP"TRUE";
"B \NAC \NWC"12;
"S \NAC"
BN"7"173;
%"TAP"
"1","(-2875,2650)","2","standard","I63";
;
CDS_LIB"standard"
BODY_TYPE"PLUMBING"
HDL_TAP"TRUE";
"B \NAC \NWC"11;
"S \NAC"
BN"5"159;
%"TAP"
"1","(-2875,2600)","2","standard","I64";
;
CDS_LIB"standard"
BODY_TYPE"PLUMBING"
HDL_TAP"TRUE";
"B \NAC \NWC"11;
"S \NAC"
BN"4"175;
%"TAP"
"1","(-2875,2550)","2","standard","I65";
;
CDS_LIB"standard"
BODY_TYPE"PLUMBING"
HDL_TAP"TRUE";
"B \NAC \NWC"11;
"S \NAC"
BN"3"158;
%"TAP"
"1","(-2875,2700)","2","standard","I66";
;
CDS_LIB"standard"
BODY_TYPE"PLUMBING"
HDL_TAP"TRUE";
"B \NAC \NWC"11;
"S \NAC"
BN"6"160;
%"TAP"
"1","(-2875,2750)","2","standard","I67";
;
CDS_LIB"standard"
BODY_TYPE"PLUMBING"
HDL_TAP"TRUE";
"B \NAC \NWC"11;
"S \NAC"
BN"7"176;
%"TAP"
"1","(-2875,3450)","2","standard","I68";
;
CDS_LIB"standard"
BODY_TYPE"PLUMBING"
HDL_TAP"TRUE";
"B \NAC \NWC"14;
"S \NAC"
BN"0"77;
%"TAP"
"1","(-2875,3550)","2","standard","I69";
;
CDS_LIB"standard"
BODY_TYPE"PLUMBING"
HDL_TAP"TRUE";
"B \NAC \NWC"14;
"S \NAC"
BN"2"169;
%"TAP"
"1","(-2875,3500)","2","standard","I70";
;
CDS_LIB"standard"
BODY_TYPE"PLUMBING"
HDL_TAP"TRUE";
"B \NAC \NWC"14;
"S \NAC"
BN"1"76;
%"TAP"
"1","(-2875,3700)","2","standard","I71";
;
CDS_LIB"standard"
BODY_TYPE"PLUMBING"
HDL_TAP"TRUE";
"B \NAC \NWC"14;
"S \NAC"
BN"5"163;
%"TAP"
"1","(-2875,3750)","2","standard","I72";
;
CDS_LIB"standard"
BODY_TYPE"PLUMBING"
HDL_TAP"TRUE";
"B \NAC \NWC"14;
"S \NAC"
BN"6"161;
%"TAP"
"1","(-2875,3600)","2","standard","I73";
;
CDS_LIB"standard"
BODY_TYPE"PLUMBING"
HDL_TAP"TRUE";
"B \NAC \NWC"14;
"S \NAC"
BN"3"167;
%"TAP"
"1","(-2875,3650)","2","standard","I74";
;
CDS_LIB"standard"
BODY_TYPE"PLUMBING"
HDL_TAP"TRUE";
"B \NAC \NWC"14;
"S \NAC"
BN"4"165;
%"TAP"
"1","(-2875,3900)","2","standard","I75";
;
CDS_LIB"standard"
BODY_TYPE"PLUMBING"
HDL_TAP"TRUE";
"B \NAC \NWC"13;
"S \NAC"
BN"1"171;
%"TAP"
"1","(-2875,3850)","2","standard","I76";
;
CDS_LIB"standard"
BODY_TYPE"PLUMBING"
HDL_TAP"TRUE";
"B \NAC \NWC"13;
"S \NAC"
BN"0"172;
%"TAP"
"1","(-2875,4050)","2","standard","I77";
;
CDS_LIB"standard"
BODY_TYPE"PLUMBING"
HDL_TAP"TRUE";
"B \NAC \NWC"13;
"S \NAC"
BN"4"166;
%"TAP"
"1","(-2875,4000)","2","standard","I78";
;
CDS_LIB"standard"
BODY_TYPE"PLUMBING"
HDL_TAP"TRUE";
"B \NAC \NWC"13;
"S \NAC"
BN"3"168;
%"TAP"
"1","(-2875,3950)","2","standard","I79";
;
CDS_LIB"standard"
BODY_TYPE"PLUMBING"
HDL_TAP"TRUE";
"B \NAC \NWC"13;
"S \NAC"
BN"2"170;
%"TAP"
"1","(-2875,4100)","2","standard","I80";
;
CDS_LIB"standard"
BODY_TYPE"PLUMBING"
HDL_TAP"TRUE";
"B \NAC \NWC"13;
"S \NAC"
BN"5"164;
%"TAP"
"1","(-2875,4150)","2","standard","I81";
;
CDS_LIB"standard"
BODY_TYPE"PLUMBING"
HDL_TAP"TRUE";
"B \NAC \NWC"13;
"S \NAC"
BN"6"162;
%"TAP"
"1","(-1225,2300)","0","standard","I82";
;
CDS_LIB"standard"
BODY_TYPE"PLUMBING"
HDL_TAP"TRUE";
"B \NAC \NWC"15;
"S \NAC"
BN"27"117;
%"TAP"
"1","(-1225,2350)","0","standard","I83";
;
CDS_LIB"standard"
BODY_TYPE"PLUMBING"
HDL_TAP"TRUE";
"B \NAC \NWC"15;
"S \NAC"
BN"28"118;
%"TAP"
"1","(-1225,2400)","0","standard","I84";
;
CDS_LIB"standard"
BODY_TYPE"PLUMBING"
HDL_TAP"TRUE";
"B \NAC \NWC"15;
"S \NAC"
BN"29"80;
%"TAP"
"1","(-1225,2500)","0","standard","I85";
;
CDS_LIB"standard"
BODY_TYPE"PLUMBING"
HDL_TAP"TRUE";
"B \NAC \NWC"15;
"S \NAC"
BN"31"79;
%"TAP"
"1","(-1225,2450)","0","standard","I86";
;
CDS_LIB"standard"
BODY_TYPE"PLUMBING"
HDL_TAP"TRUE";
"B \NAC \NWC"15;
"S \NAC"
BN"30"119;
%"TAP"
"1","(-1225,2600)","0","standard","I87";
;
CDS_LIB"standard"
BODY_TYPE"PLUMBING"
HDL_TAP"TRUE";
"B \NAC \NWC"10;
"S \NAC"
BN"0"120;
%"TAP"
"1","(-1225,2650)","0","standard","I88";
;
CDS_LIB"standard"
BODY_TYPE"PLUMBING"
HDL_TAP"TRUE";
"B \NAC \NWC"10;
"S \NAC"
BN"1"121;
%"TAP"
"1","(-1225,2800)","0","standard","I89";
;
CDS_LIB"standard"
BODY_TYPE"PLUMBING"
HDL_TAP"TRUE";
"B \NAC \NWC"10;
"S \NAC"
BN"4"124;
%"TAP"
"1","(-1225,2750)","0","standard","I90";
;
CDS_LIB"standard"
BODY_TYPE"PLUMBING"
HDL_TAP"TRUE";
"B \NAC \NWC"10;
"S \NAC"
BN"3"123;
%"TAP"
"1","(-1225,2700)","0","standard","I91";
;
CDS_LIB"standard"
BODY_TYPE"PLUMBING"
HDL_TAP"TRUE";
"B \NAC \NWC"10;
"S \NAC"
BN"2"122;
%"TAP"
"1","(-1225,2850)","0","standard","I92";
;
CDS_LIB"standard"
BODY_TYPE"PLUMBING"
HDL_TAP"TRUE";
"B \NAC \NWC"10;
"S \NAC"
BN"5"125;
%"TAP"
"1","(-1225,2900)","0","standard","I93";
;
CDS_LIB"standard"
BODY_TYPE"PLUMBING"
HDL_TAP"TRUE";
"B \NAC \NWC"10;
"S \NAC"
BN"6"126;
%"TAP"
"1","(-1225,3050)","0","standard","I94";
;
CDS_LIB"standard"
BODY_TYPE"PLUMBING"
HDL_TAP"TRUE";
"B \NAC \NWC"10;
"S \NAC"
BN"9"78;
%"TAP"
"1","(-1225,2950)","0","standard","I95";
;
CDS_LIB"standard"
BODY_TYPE"PLUMBING"
HDL_TAP"TRUE";
"B \NAC \NWC"10;
"S \NAC"
BN"7"127;
%"TAP"
"1","(-1225,3000)","0","standard","I96";
;
CDS_LIB"standard"
BODY_TYPE"PLUMBING"
HDL_TAP"TRUE";
"B \NAC \NWC"10;
"S \NAC"
BN"8"128;
%"TAP"
"1","(-1225,3100)","0","standard","I97";
;
CDS_LIB"standard"
BODY_TYPE"PLUMBING"
HDL_TAP"TRUE";
"B \NAC \NWC"10;
"S \NAC"
BN"10"129;
%"TAP"
"1","(-1225,3150)","0","standard","I98";
;
CDS_LIB"standard"
BODY_TYPE"PLUMBING"
HDL_TAP"TRUE";
"B \NAC \NWC"10;
"S \NAC"
BN"11"130;
%"TAP"
"1","(-1225,3250)","0","standard","I99";
;
CDS_LIB"standard"
BODY_TYPE"PLUMBING"
HDL_TAP"TRUE";
"B \NAC \NWC"10;
"S \NAC"
BN"13"71;
END.
